# T6G (Grand Teton) — schematic netlist excerpt (pin names and nets, part order shuffled) for the footprints in the layout excerpt that follows; sources: Cadence DE-HDL packaged netlist, KiCad conversion of 04192023_DAF0TMB3IC0_F0TG_MB_C_brd_V02_OCP.brd

R3717  Q_RES  0 5% CHIP  pkg 0402LF  page 252 : A = SMB_LM75_1_3V3AUX_SCL_R ; B = SMB_LM75_1_3V3AUX_SCL
R659  Q_RES  1K 1% CHIP  pkg 0402LF  page 77 : A = PVDD18_S5_P0 ; B = SPI_CPU0_TPM_CS_N

(kicad_pcb
	(version 20260206)
	(generator "pcbnew")
	(generator_version "10.0")
	(general
		(thickness 1.6)
		(legacy_teardrops no)
	)
	(paper "A4")
	(title_block
		(title "04192023_DAF0TMB3IC0_F0TG_MB_C_brd_V02_OCP.brd")
		(comment 1 "Grand Teton / footprints 944-945 of 8354")
	)
	(layers
		(0 "F.Cu" signal "TOP")
		(4 "In1.Cu" signal "GND")
		(6 "In2.Cu" signal "IN1")
		(8 "In3.Cu" signal "GND1")
		(10 "In4.Cu" signal "IN2")
		(12 "In5.Cu" signal "GND2")
		(14 "In6.Cu" signal "IN3")
		(16 "In7.Cu" signal "GND3")
		(18 "In8.Cu" signal "VCC")
		(20 "In9.Cu" signal "VCC1")
		(22 "In10.Cu" signal "GND4")
		(24 "In11.Cu" signal "IN4")
		(26 "In12.Cu" signal "GND5")
		(28 "In13.Cu" signal "IN5")
		(30 "In14.Cu" signal "GND6")
		(32 "In15.Cu" signal "IN6")
		(34 "In16.Cu" signal "GND7")
		(2 "B.Cu" signal "BOTTOM")
		(9 "F.Adhes" user "F.Adhesive")
		(11 "B.Adhes" user "B.Adhesive")
		(13 "F.Paste" user "Package Geometry/Pastemask Top")
		(15 "B.Paste" user "Package Geometry/Pastemask Bottom")
		(5 "F.SilkS" user "Ref Des/Silkscreen Top")
		(7 "B.SilkS" user "Ref Des/Silkscreen Bottom")
		(1 "F.Mask" user "Board Geometry/Soldermask Top")
		(3 "B.Mask" user "Board Geometry/Soldermask Bottom")
		(17 "Dwgs.User" user "User.Drawings")
		(19 "Cmts.User" user "User.Comments")
		(21 "Eco1.User" user "User.Eco1")
		(23 "Eco2.User" user "User.Eco2")
		(25 "Edge.Cuts" user "Board Geometry/Outline")
		(27 "Margin" user)
		(31 "F.CrtYd" user "Package Geometry/Place Bound Top")
		(29 "B.CrtYd" user "Package Geometry/Place Bound Bottom")
		(35 "F.Fab" user "Ref Des/Assembly Top")
		(33 "B.Fab" user "Ref Des/Assembly Bottom")
	)
	(footprint ""
		(layer "F.Cu")
		(at 257.242056 -116.87937 180)
		(property "Reference" "R3717"
			(at 0 0 180)
			(layer "F.SilkS")
			(hide yes)
			(effects
				(font
					(size 1.27 1.27)
				)
			)
		)
		(property "Value" ""
			(at 0 0 180)
			(layer "F.Fab")
			(effects
				(font
					(size 1.27 1.27)
				)
			)
		)
		(duplicate_pad_numbers_are_jumpers no)
		(fp_line
			(start 0.7874 0.4064)
			(end -0.7874 0.4064)
			(stroke
				(width 0.1524)
				(type default)
			)
			(layer "F.SilkS")
		)
		(fp_line
			(start 0.7874 -0.4064)
			(end 0.7874 0.4064)
			(stroke
				(width 0.1524)
				(type default)
			)
			(layer "F.SilkS")
		)
		(fp_line
			(start -0.7874 0.4064)
			(end -0.7874 -0.4064)
			(stroke
				(width 0.1524)
				(type default)
			)
			(layer "F.SilkS")
		)
		(fp_line
			(start -0.7874 -0.4064)
			(end 0.7874 -0.4064)
			(stroke
				(width 0.1524)
				(type default)
			)
			(layer "F.SilkS")
		)
		(fp_line
			(start 0.67945 0.3048)
			(end 0.120396 0.3048)
			(stroke
				(width 0.1)
				(type default)
			)
			(layer "F.Fab")
		)
		(fp_line
			(start 0.67945 -0.3048)
			(end 0.67945 0.3048)
			(stroke
				(width 0.1)
				(type default)
			)
			(layer "F.Fab")
		)
		(fp_line
			(start 0.12065 -0.2794)
			(end 0.12065 -0.3048)
			(stroke
				(width 0.1)
				(type default)
			)
			(layer "F.Fab")
		)
		(fp_line
			(start 0.12065 -0.3048)
			(end 0.67945 -0.3048)
			(stroke
				(width 0.1)
				(type default)
			)
			(layer "F.Fab")
		)
		(fp_line
			(start 0.120396 0.3048)
			(end 0.120396 0.2794)
			(stroke
				(width 0.1)
				(type default)
			)
			(layer "F.Fab")
		)
		(fp_line
			(start 0.120396 0.2794)
			(end -0.12065 0.2794)
			(stroke
				(width 0.1)
				(type default)
			)
			(layer "F.Fab")
		)
		(fp_line
			(start -0.12065 0.3048)
			(end -0.67945 0.3048)
			(stroke
				(width 0.1)
				(type default)
			)
			(layer "F.Fab")
		)
		(fp_line
			(start -0.12065 0.2794)
			(end -0.12065 0.3048)
			(stroke
				(width 0.1)
				(type default)
			)
			(layer "F.Fab")
		)
		(fp_line
			(start -0.12065 -0.2794)
			(end 0.12065 -0.2794)
			(stroke
				(width 0.1)
				(type default)
			)
			(layer "F.Fab")
		)
		(fp_line
			(start -0.12065 -0.305054)
			(end -0.12065 -0.2794)
			(stroke
				(width 0.1)
				(type default)
			)
			(layer "F.Fab")
		)
		(fp_line
			(start -0.67945 0.3048)
			(end -0.67945 -0.305054)
			(stroke
				(width 0.1)
				(type default)
			)
			(layer "F.Fab")
		)
		(fp_line
			(start -0.67945 -0.305054)
			(end -0.12065 -0.305054)
			(stroke
				(width 0.1)
				(type default)
			)
			(layer "F.Fab")
		)
		(pad "1" smd circle
			(at -0.40005 0 180)
			(size 0 0)
			(layers "F.Cu" "F.Mask" "F.Paste")
			(net "SMB_LM75_1_3V3AUX_SCL_R")
		)
		(pad "2" smd circle
			(at 0.40005 0 180)
			(size 0 0)
			(layers "F.Cu" "F.Mask" "F.Paste")
			(net "SMB_LM75_1_3V3AUX_SCL")
		)
	)
	(footprint ""
		(layer "F.Cu")
		(at 264.478516 -135.654796 180)
		(property "Reference" "R659"
			(at 0 0 180)
			(layer "F.SilkS")
			(hide yes)
			(effects
				(font
					(size 1.27 1.27)
				)
			)
		)
		(property "Value" ""
			(at 0 0 180)
			(layer "F.Fab")
			(effects
				(font
					(size 1.27 1.27)
				)
			)
		)
		(duplicate_pad_numbers_are_jumpers no)
		(fp_line
			(start 0.7874 0.4064)
			(end -0.7874 0.4064)
			(stroke
				(width 0.1524)
				(type default)
			)
			(layer "F.SilkS")
		)
		(fp_line
			(start 0.7874 -0.4064)
			(end 0.7874 0.4064)
			(stroke
				(width 0.1524)
				(type default)
			)
			(layer "F.SilkS")
		)
		(fp_line
			(start -0.7874 0.4064)
			(end -0.7874 -0.4064)
			(stroke
				(width 0.1524)
				(type default)
			)
			(layer "F.SilkS")
		)
		(fp_line
			(start -0.7874 -0.4064)
			(end 0.7874 -0.4064)
			(stroke
				(width 0.1524)
				(type default)
			)
			(layer "F.SilkS")
		)
		(fp_line
			(start 0.67945 0.3048)
			(end 0.120396 0.3048)
			(stroke
				(width 0.1)
				(type default)
			)
			(layer "F.Fab")
		)
		(fp_line
			(start 0.67945 -0.3048)
			(end 0.67945 0.3048)
			(stroke
				(width 0.1)
				(type default)
			)
			(layer "F.Fab")
		)
		(fp_line
			(start 0.12065 -0.2794)
			(end 0.12065 -0.3048)
			(stroke
				(width 0.1)
				(type default)
			)
			(layer "F.Fab")
		)
		(fp_line
			(start 0.12065 -0.3048)
			(end 0.67945 -0.3048)
			(stroke
				(width 0.1)
				(type default)
			)
			(layer "F.Fab")
		)
		(fp_line
			(start 0.120396 0.3048)
			(end 0.120396 0.2794)
			(stroke
				(width 0.1)
				(type default)
			)
			(layer "F.Fab")
		)
		(fp_line
			(start 0.120396 0.2794)
			(end -0.12065 0.2794)
			(stroke
				(width 0.1)
				(type default)
			)
			(layer "F.Fab")
		)
		(fp_line
			(start -0.12065 0.3048)
			(end -0.67945 0.3048)
			(stroke
				(width 0.1)
				(type default)
			)
			(layer "F.Fab")
		)
		(fp_line
			(start -0.12065 0.2794)
			(end -0.12065 0.3048)
			(stroke
				(width 0.1)
				(type default)
			)
			(layer "F.Fab")
		)
		(fp_line
			(start -0.12065 -0.2794)
			(end 0.12065 -0.2794)
			(stroke
				(width 0.1)
				(type default)
			)
			(layer "F.Fab")
		)
		(fp_line
			(start -0.12065 -0.305054)
			(end -0.12065 -0.2794)
			(stroke
				(width 0.1)
				(type default)
			)
			(layer "F.Fab")
		)
		(fp_line
			(start -0.67945 0.3048)
			(end -0.67945 -0.305054)
			(stroke
				(width 0.1)
				(type default)
			)
			(layer "F.Fab")
		)
		(fp_line
			(start -0.67945 -0.305054)
			(end -0.12065 -0.305054)
			(stroke
				(width 0.1)
				(type default)
			)
			(layer "F.Fab")
		)
		(pad "1" smd circle
			(at -0.40005 0 180)
			(size 0 0)
			(layers "F.Cu" "F.Mask" "F.Paste")
			(net "PVDD18_S5_P0")
		)
		(pad "2" smd circle
			(at 0.40005 0 180)
			(size 0 0)
			(layers "F.Cu" "F.Mask" "F.Paste")
			(net "SPI_CPU0_TPM_CS_N")
		)
	)
)
